(kicad_pcb
	(version 20260206)
	(generator "pcbnew")
	(generator_version "10.0")
	(general
		(thickness 1.6)
		(legacy_teardrops no)
	)
	(paper "A4")
	(title_block
		(title "panther-plus-userver — 13130-1b_20150205.brd")
		(comment 1 "Honey Badger (Wiwynn) / footprint 406 of 1509 (DIMM2), pads 30-36 of 210")
	)
	(layers
		(0 "F.Cu" signal "TOP")
		(4 "In1.Cu" signal "L2")
		(6 "In2.Cu" signal "L3")
		(8 "In3.Cu" signal "L4")
		(10 "In4.Cu" signal "L5")
		(12 "In5.Cu" signal "L6")
		(14 "In6.Cu" signal "L7")
		(16 "In7.Cu" signal "L8")
		(18 "In8.Cu" signal "L9")
		(20 "In9.Cu" signal "L10")
		(22 "In10.Cu" signal "L11")
		(2 "B.Cu" signal "BOTTOM")
		(9 "F.Adhes" user "F.Adhesive")
		(11 "B.Adhes" user "B.Adhesive")
		(13 "F.Paste" user "Package Geometry/Pastemask Top")
		(15 "B.Paste" user "Package Geometry/Pastemask Bottom")
		(5 "F.SilkS" user "Ref Des/Silkscreen Top")
		(7 "B.SilkS" user "Ref Des/Silkscreen Bottom")
		(1 "F.Mask" user "Board Geometry/Soldermask Top")
		(3 "B.Mask" user "Board Geometry/Soldermask Bottom")
		(17 "Dwgs.User" user "User.Drawings")
		(19 "Cmts.User" user "User.Comments")
		(21 "Eco1.User" user "User.Eco1")
		(23 "Eco2.User" user "User.Eco2")
		(25 "Edge.Cuts" user "Board Geometry/Outline")
		(27 "Margin" user)
		(31 "F.CrtYd" user "Package Geometry/Place Bound Top")
		(29 "B.CrtYd" user "Package Geometry/Place Bound Bottom")
		(35 "F.Fab" user "Ref Des/Assembly Top")
		(33 "B.Fab" user "Ref Des/Assembly Bottom")
	)
	(footprint ""
		(layer "F.Cu")
		(at 158.500064 -66.699892 180)
		(property "Reference" "DIMM2"
			(at 0 0 180)
			(layer "F.SilkS")
			(hide yes)
			(effects
				(font
					(size 1.27 1.27)
				)
			)
		)
		(property "Value" "DDR3-204P-174-COLAY-1-GP"
			(at -40.682164 -17.468088 180)
			(unlocked yes)
			(layer "F.Fab")
			(hide yes)
			(effects
				(font
					(size 1.016 1.016)
					(thickness 0.1524)
				)
			)
		)
		(property "Device Type" "AS0A626-H8SN-7H-COLAY-1"
			(at -40.682164 -18.992088 180)
			(unlocked yes)
			(layer "F.Fab")
			(hide yes)
			(effects
				(font
					(size 1.016 1.016)
					(thickness 0.1524)
				)
			)
		)
		(duplicate_pad_numbers_are_jumpers no)
		(pad "28" smd custom
			(at -23.550118 -4.106672 180)
			(size 0.1143 0.1143)
			(layers "F.Cu" "F.Mask" "F.Paste")
			(net "GND")
			(options
				(clearance outline)
				(anchor circle)
			)
			(primitives
				(gr_poly
					(pts
						(xy 0 0.9017) (xy -0.03175 0.89916) (xy -0.0635 0.889) (xy -0.09144 0.87376) (xy -0.11684 0.85344)
						(xy -0.13716 0.82804) (xy -0.1524 0.8001) (xy -0.16256 0.76835) (xy -0.1651 0.7366) (xy -0.1651 0.19685)
						(xy -0.17272 0.18923) (xy -0.17907 0.18034) (xy -0.18669 0.17145) (xy -0.19177 0.16256) (xy -0.19812 0.15367)
						(xy -0.20828 0.13335) (xy -0.21971 0.10287) (xy -0.22225 0.09271) (xy -0.22479 0.08128) (xy -0.22606 0.07112)
						(xy -0.2286 0.05969) (xy -0.2286 0.01651) (xy -0.22606 0.00508) (xy -0.22479 -0.00508) (xy -0.22225 -0.01651)
						(xy -0.21971 -0.02667) (xy -0.20828 -0.05715) (xy -0.19812 -0.07747) (xy -0.19177 -0.08636) (xy -0.18669 -0.09525)
						(xy -0.17907 -0.10414) (xy -0.17272 -0.11303) (xy -0.1651 -0.12065) (xy -0.1651 -0.7366) (xy -0.16256 -0.76835)
						(xy -0.1524 -0.8001) (xy -0.13716 -0.82804) (xy -0.11684 -0.85344) (xy -0.09144 -0.87376) (xy -0.0635 -0.889)
						(xy -0.03175 -0.89916) (xy 0 -0.9017) (xy 0.03175 -0.89916) (xy 0.0635 -0.889) (xy 0.09144 -0.87376)
						(xy 0.11684 -0.85344) (xy 0.13716 -0.82804) (xy 0.1524 -0.8001) (xy 0.16256 -0.76835) (xy 0.1651 -0.7366)
						(xy 0.1651 -0.11938) (xy 0.17272 -0.11176) (xy 0.19812 -0.0762) (xy 0.2032 -0.06604) (xy 0.20701 -0.05715)
						(xy 0.21209 -0.04699) (xy 0.2159 -0.03683) (xy 0.21844 -0.02667) (xy 0.22225 -0.01524) (xy 0.22352 -0.00508)
						(xy 0.22606 0.00508) (xy 0.22733 0.01651) (xy 0.22733 0.02667) (xy 0.2286 0.0381) (xy 0.22733 0.04953)
						(xy 0.22733 0.05969) (xy 0.22606 0.07112) (xy 0.22352 0.08128) (xy 0.22225 0.09144) (xy 0.21844 0.10287)
						(xy 0.2159 0.11303) (xy 0.21209 0.12319) (xy 0.20701 0.13335) (xy 0.2032 0.14224) (xy 0.19812 0.1524)
						(xy 0.17272 0.18796) (xy 0.1651 0.19558) (xy 0.1651 0.7366) (xy 0.16256 0.76835) (xy 0.1524 0.8001)
						(xy 0.13716 0.82804) (xy 0.11684 0.85344) (xy 0.09144 0.87376) (xy 0.0635 0.889) (xy 0.03175 0.89916)
					)
					(width 0)
					(fill yes)
				)
			)
		)
		(pad "29" smd custom
			(at -23.24989 4.106672 180)
			(size 0.1143 0.1143)
			(layers "F.Cu" "F.Mask" "F.Paste")
			(net "GND")
			(options
				(clearance outline)
				(anchor circle)
			)
			(primitives
				(gr_poly
					(pts
						(xy 0 0.9017) (xy -0.03175 0.89916) (xy -0.0635 0.889) (xy -0.09144 0.87376) (xy -0.11684 0.85344)
						(xy -0.13716 0.82804) (xy -0.1524 0.8001) (xy -0.16256 0.76835) (xy -0.1651 0.7366) (xy -0.1651 -0.13462)
						(xy -0.17272 -0.14224) (xy -0.19812 -0.1778) (xy -0.2032 -0.18796) (xy -0.20701 -0.19685) (xy -0.21209 -0.20701)
						(xy -0.2159 -0.21717) (xy -0.21844 -0.22733) (xy -0.22225 -0.23876) (xy -0.22352 -0.24892) (xy -0.22606 -0.25908)
						(xy -0.22733 -0.27051) (xy -0.22733 -0.28067) (xy -0.2286 -0.2921) (xy -0.22733 -0.30353) (xy -0.22733 -0.31369)
						(xy -0.22606 -0.32512) (xy -0.22352 -0.33528) (xy -0.22225 -0.34544) (xy -0.21844 -0.35687) (xy -0.2159 -0.36703)
						(xy -0.21209 -0.37719) (xy -0.20701 -0.38735) (xy -0.2032 -0.39624) (xy -0.19812 -0.4064) (xy -0.17272 -0.44196)
						(xy -0.1651 -0.44958) (xy -0.1651 -0.7366) (xy -0.16256 -0.76835) (xy -0.1524 -0.8001) (xy -0.13716 -0.82804)
						(xy -0.11684 -0.85344) (xy -0.09144 -0.87376) (xy -0.0635 -0.889) (xy -0.03175 -0.89916) (xy 0 -0.9017)
						(xy 0.03175 -0.89916) (xy 0.0635 -0.889) (xy 0.09144 -0.87376) (xy 0.11684 -0.85344) (xy 0.13716 -0.82804)
						(xy 0.1524 -0.8001) (xy 0.16256 -0.76835) (xy 0.1651 -0.7366) (xy 0.1651 -0.44958) (xy 0.17272 -0.44196)
						(xy 0.19812 -0.4064) (xy 0.2032 -0.39624) (xy 0.20701 -0.38735) (xy 0.21209 -0.37719) (xy 0.2159 -0.36703)
						(xy 0.21844 -0.35687) (xy 0.22225 -0.34544) (xy 0.22352 -0.33528) (xy 0.22606 -0.32512) (xy 0.22733 -0.31369)
						(xy 0.22733 -0.30353) (xy 0.2286 -0.2921) (xy 0.22733 -0.28067) (xy 0.22733 -0.27051) (xy 0.22606 -0.25908)
						(xy 0.22352 -0.24892) (xy 0.22225 -0.23876) (xy 0.21844 -0.22733) (xy 0.2159 -0.21717) (xy 0.21209 -0.20701)
						(xy 0.20701 -0.19685) (xy 0.2032 -0.18796) (xy 0.19812 -0.1778) (xy 0.17272 -0.14224) (xy 0.1651 -0.13462)
						(xy 0.1651 0.7366) (xy 0.16256 0.76835) (xy 0.1524 0.8001) (xy 0.13716 0.82804) (xy 0.11684 0.85344)
						(xy 0.09144 0.87376) (xy 0.0635 0.889) (xy 0.03175 0.89916)
					)
					(width 0)
					(fill yes)
				)
			)
		)
		(pad "30" smd custom
			(at -22.949916 -4.106672 180)
			(size 0.1143 0.1143)
			(layers "F.Cu" "F.Mask" "F.Paste")
			(net "M_A_RESET#")
			(options
				(clearance outline)
				(anchor circle)
			)
			(primitives
				(gr_poly
					(pts
						(xy 0 0.9017) (xy -0.03175 0.89916) (xy -0.0635 0.889) (xy -0.09144 0.87376) (xy -0.11684 0.85344)
						(xy -0.13716 0.82804) (xy -0.1524 0.8001) (xy -0.16256 0.76835) (xy -0.1651 0.7366) (xy -0.1651 0.44958)
						(xy -0.17272 0.44196) (xy -0.19812 0.4064) (xy -0.2032 0.39624) (xy -0.20701 0.38735) (xy -0.21209 0.37719)
						(xy -0.2159 0.36703) (xy -0.21844 0.35687) (xy -0.22225 0.34544) (xy -0.22352 0.33528) (xy -0.22606 0.32512)
						(xy -0.22733 0.31369) (xy -0.22733 0.30353) (xy -0.2286 0.2921) (xy -0.22733 0.28067) (xy -0.22733 0.27051)
						(xy -0.22606 0.25908) (xy -0.22352 0.24892) (xy -0.22225 0.23876) (xy -0.21844 0.22733) (xy -0.2159 0.21717)
						(xy -0.21209 0.20701) (xy -0.20701 0.19685) (xy -0.2032 0.18796) (xy -0.19812 0.1778) (xy -0.17272 0.14224)
						(xy -0.1651 0.13462) (xy -0.1651 -0.7366) (xy -0.16256 -0.76835) (xy -0.1524 -0.8001) (xy -0.13716 -0.82804)
						(xy -0.11684 -0.85344) (xy -0.09144 -0.87376) (xy -0.0635 -0.889) (xy -0.03175 -0.89916) (xy 0 -0.9017)
						(xy 0.03175 -0.89916) (xy 0.0635 -0.889) (xy 0.09144 -0.87376) (xy 0.11684 -0.85344) (xy 0.13716 -0.82804)
						(xy 0.1524 -0.8001) (xy 0.16256 -0.76835) (xy 0.1651 -0.7366) (xy 0.1651 0.13462) (xy 0.17272 0.14224)
						(xy 0.19812 0.1778) (xy 0.2032 0.18796) (xy 0.20701 0.19685) (xy 0.21209 0.20701) (xy 0.2159 0.21717)
						(xy 0.21844 0.22733) (xy 0.22225 0.23876) (xy 0.22352 0.24892) (xy 0.22606 0.25908) (xy 0.22733 0.27051)
						(xy 0.22733 0.28067) (xy 0.2286 0.2921) (xy 0.22733 0.30353) (xy 0.22733 0.31369) (xy 0.22606 0.32512)
						(xy 0.22352 0.33528) (xy 0.22225 0.34544) (xy 0.21844 0.35687) (xy 0.2159 0.36703) (xy 0.21209 0.37719)
						(xy 0.20701 0.38735) (xy 0.2032 0.39624) (xy 0.19812 0.4064) (xy 0.17272 0.44196) (xy 0.1651 0.44958)
						(xy 0.1651 0.7366) (xy 0.16256 0.76835) (xy 0.1524 0.8001) (xy 0.13716 0.82804) (xy 0.11684 0.85344)
						(xy 0.09144 0.87376) (xy 0.0635 0.889) (xy 0.03175 0.89916)
					)
					(width 0)
					(fill yes)
				)
			)
		)
		(pad "31" smd custom
			(at -22.649942 4.106672 180)
			(size 0.1143 0.1143)
			(layers "F.Cu" "F.Mask" "F.Paste")
			(net "M_A_DQ14")
			(options
				(clearance outline)
				(anchor circle)
			)
			(primitives
				(gr_poly
					(pts
						(xy 0 0.9017) (xy -0.03175 0.89916) (xy -0.0635 0.889) (xy -0.09144 0.87376) (xy -0.11684 0.85344)
						(xy -0.13716 0.82804) (xy -0.1524 0.8001) (xy -0.16256 0.76835) (xy -0.1651 0.7366) (xy -0.1651 0.11938)
						(xy -0.17272 0.11176) (xy -0.19812 0.0762) (xy -0.2032 0.06604) (xy -0.20701 0.05715) (xy -0.21209 0.04699)
						(xy -0.2159 0.03683) (xy -0.21844 0.02667) (xy -0.22225 0.01524) (xy -0.22352 0.00508) (xy -0.22606 -0.00508)
						(xy -0.22733 -0.01651) (xy -0.22733 -0.02667) (xy -0.2286 -0.0381) (xy -0.22733 -0.04953) (xy -0.22733 -0.05969)
						(xy -0.22606 -0.07112) (xy -0.22352 -0.08128) (xy -0.22225 -0.09144) (xy -0.21844 -0.10287) (xy -0.2159 -0.11303)
						(xy -0.21209 -0.12319) (xy -0.20701 -0.13335) (xy -0.2032 -0.14224) (xy -0.19812 -0.1524) (xy -0.17272 -0.18796)
						(xy -0.1651 -0.19558) (xy -0.1651 -0.7366) (xy -0.16256 -0.76835) (xy -0.1524 -0.8001) (xy -0.13716 -0.82804)
						(xy -0.11684 -0.85344) (xy -0.09144 -0.87376) (xy -0.0635 -0.889) (xy -0.03175 -0.89916) (xy 0 -0.9017)
						(xy 0.03175 -0.89916) (xy 0.0635 -0.889) (xy 0.09144 -0.87376) (xy 0.11684 -0.85344) (xy 0.13716 -0.82804)
						(xy 0.1524 -0.8001) (xy 0.16256 -0.76835) (xy 0.1651 -0.7366) (xy 0.1651 -0.19685) (xy 0.17272 -0.18923)
						(xy 0.17907 -0.18034) (xy 0.18669 -0.17145) (xy 0.19177 -0.16256) (xy 0.19812 -0.15367) (xy 0.20828 -0.13335)
						(xy 0.21971 -0.10287) (xy 0.22225 -0.09271) (xy 0.22479 -0.08128) (xy 0.22606 -0.07112) (xy 0.2286 -0.05969)
						(xy 0.2286 -0.01651) (xy 0.22606 -0.00508) (xy 0.22479 0.00508) (xy 0.22225 0.01651) (xy 0.21971 0.02667)
						(xy 0.20828 0.05715) (xy 0.19812 0.07747) (xy 0.19177 0.08636) (xy 0.18669 0.09525) (xy 0.17907 0.10414)
						(xy 0.17272 0.11303) (xy 0.1651 0.12065) (xy 0.1651 0.7366) (xy 0.16256 0.76835) (xy 0.1524 0.8001)
						(xy 0.13716 0.82804) (xy 0.11684 0.85344) (xy 0.09144 0.87376) (xy 0.0635 0.889) (xy 0.03175 0.89916)
					)
					(width 0)
					(fill yes)
				)
			)
		)
		(pad "32" smd custom
			(at -22.349968 -4.106672 180)
			(size 0.1143 0.1143)
			(layers "F.Cu" "F.Mask" "F.Paste")
			(net "GND")
			(options
				(clearance outline)
				(anchor circle)
			)
			(primitives
				(gr_poly
					(pts
						(xy 0 0.9017) (xy -0.03175 0.89916) (xy -0.0635 0.889) (xy -0.09144 0.87376) (xy -0.11684 0.85344)
						(xy -0.13716 0.82804) (xy -0.1524 0.8001) (xy -0.16256 0.76835) (xy -0.1651 0.7366) (xy -0.1651 0.19685)
						(xy -0.17272 0.18923) (xy -0.17907 0.18034) (xy -0.18669 0.17145) (xy -0.19177 0.16256) (xy -0.19812 0.15367)
						(xy -0.20828 0.13335) (xy -0.21971 0.10287) (xy -0.22225 0.09271) (xy -0.22479 0.08128) (xy -0.22606 0.07112)
						(xy -0.2286 0.05969) (xy -0.2286 0.01651) (xy -0.22606 0.00508) (xy -0.22479 -0.00508) (xy -0.22225 -0.01651)
						(xy -0.21971 -0.02667) (xy -0.20828 -0.05715) (xy -0.19812 -0.07747) (xy -0.19177 -0.08636) (xy -0.18669 -0.09525)
						(xy -0.17907 -0.10414) (xy -0.17272 -0.11303) (xy -0.1651 -0.12065) (xy -0.1651 -0.7366) (xy -0.16256 -0.76835)
						(xy -0.1524 -0.8001) (xy -0.13716 -0.82804) (xy -0.11684 -0.85344) (xy -0.09144 -0.87376) (xy -0.0635 -0.889)
						(xy -0.03175 -0.89916) (xy 0 -0.9017) (xy 0.03175 -0.89916) (xy 0.0635 -0.889) (xy 0.09144 -0.87376)
						(xy 0.11684 -0.85344) (xy 0.13716 -0.82804) (xy 0.1524 -0.8001) (xy 0.16256 -0.76835) (xy 0.1651 -0.7366)
						(xy 0.1651 -0.11938) (xy 0.17272 -0.11176) (xy 0.19812 -0.0762) (xy 0.2032 -0.06604) (xy 0.20701 -0.05715)
						(xy 0.21209 -0.04699) (xy 0.2159 -0.03683) (xy 0.21844 -0.02667) (xy 0.22225 -0.01524) (xy 0.22352 -0.00508)
						(xy 0.22606 0.00508) (xy 0.22733 0.01651) (xy 0.22733 0.02667) (xy 0.2286 0.0381) (xy 0.22733 0.04953)
						(xy 0.22733 0.05969) (xy 0.22606 0.07112) (xy 0.22352 0.08128) (xy 0.22225 0.09144) (xy 0.21844 0.10287)
						(xy 0.2159 0.11303) (xy 0.21209 0.12319) (xy 0.20701 0.13335) (xy 0.2032 0.14224) (xy 0.19812 0.1524)
						(xy 0.17272 0.18796) (xy 0.1651 0.19558) (xy 0.1651 0.7366) (xy 0.16256 0.76835) (xy 0.1524 0.8001)
						(xy 0.13716 0.82804) (xy 0.11684 0.85344) (xy 0.09144 0.87376) (xy 0.0635 0.889) (xy 0.03175 0.89916)
					)
					(width 0)
					(fill yes)
				)
			)
		)
		(pad "33" smd custom
			(at -22.049994 4.106672 180)
			(size 0.1143 0.1143)
			(layers "F.Cu" "F.Mask" "F.Paste")
			(net "M_A_DQ15")
			(options
				(clearance outline)
				(anchor circle)
			)
			(primitives
				(gr_poly
					(pts
						(xy 0 0.9017) (xy -0.03175 0.89916) (xy -0.0635 0.889) (xy -0.09144 0.87376) (xy -0.11684 0.85344)
						(xy -0.13716 0.82804) (xy -0.1524 0.8001) (xy -0.16256 0.76835) (xy -0.1651 0.7366) (xy -0.1651 -0.13462)
						(xy -0.17272 -0.14224) (xy -0.19812 -0.1778) (xy -0.2032 -0.18796) (xy -0.20701 -0.19685) (xy -0.21209 -0.20701)
						(xy -0.2159 -0.21717) (xy -0.21844 -0.22733) (xy -0.22225 -0.23876) (xy -0.22352 -0.24892) (xy -0.22606 -0.25908)
						(xy -0.22733 -0.27051) (xy -0.22733 -0.28067) (xy -0.2286 -0.2921) (xy -0.22733 -0.30353) (xy -0.22733 -0.31369)
						(xy -0.22606 -0.32512) (xy -0.22352 -0.33528) (xy -0.22225 -0.34544) (xy -0.21844 -0.35687) (xy -0.2159 -0.36703)
						(xy -0.21209 -0.37719) (xy -0.20701 -0.38735) (xy -0.2032 -0.39624) (xy -0.19812 -0.4064) (xy -0.17272 -0.44196)
						(xy -0.1651 -0.44958) (xy -0.1651 -0.7366) (xy -0.16256 -0.76835) (xy -0.1524 -0.8001) (xy -0.13716 -0.82804)
						(xy -0.11684 -0.85344) (xy -0.09144 -0.87376) (xy -0.0635 -0.889) (xy -0.03175 -0.89916) (xy 0 -0.9017)
						(xy 0.03175 -0.89916) (xy 0.0635 -0.889) (xy 0.09144 -0.87376) (xy 0.11684 -0.85344) (xy 0.13716 -0.82804)
						(xy 0.1524 -0.8001) (xy 0.16256 -0.76835) (xy 0.1651 -0.7366) (xy 0.1651 -0.44958) (xy 0.17272 -0.44196)
						(xy 0.19812 -0.4064) (xy 0.2032 -0.39624) (xy 0.20701 -0.38735) (xy 0.21209 -0.37719) (xy 0.2159 -0.36703)
						(xy 0.21844 -0.35687) (xy 0.22225 -0.34544) (xy 0.22352 -0.33528) (xy 0.22606 -0.32512) (xy 0.22733 -0.31369)
						(xy 0.22733 -0.30353) (xy 0.2286 -0.2921) (xy 0.22733 -0.28067) (xy 0.22733 -0.27051) (xy 0.22606 -0.25908)
						(xy 0.22352 -0.24892) (xy 0.22225 -0.23876) (xy 0.21844 -0.22733) (xy 0.2159 -0.21717) (xy 0.21209 -0.20701)
						(xy 0.20701 -0.19685) (xy 0.2032 -0.18796) (xy 0.19812 -0.1778) (xy 0.17272 -0.14224) (xy 0.1651 -0.13462)
						(xy 0.1651 0.7366) (xy 0.16256 0.76835) (xy 0.1524 0.8001) (xy 0.13716 0.82804) (xy 0.11684 0.85344)
						(xy 0.09144 0.87376) (xy 0.0635 0.889) (xy 0.03175 0.89916)
					)
					(width 0)
					(fill yes)
				)
			)
		)
		(pad "34" smd custom
			(at -21.75002 -4.106672 180)
			(size 0.1143 0.1143)
			(layers "F.Cu" "F.Mask" "F.Paste")
			(net "M_A_DQ10")
			(options
				(clearance outline)
				(anchor circle)
			)
			(primitives
				(gr_poly
					(pts
						(xy 0 0.9017) (xy -0.03175 0.89916) (xy -0.0635 0.889) (xy -0.09144 0.87376) (xy -0.11684 0.85344)
						(xy -0.13716 0.82804) (xy -0.1524 0.8001) (xy -0.16256 0.76835) (xy -0.1651 0.7366) (xy -0.1651 0.44958)
						(xy -0.17272 0.44196) (xy -0.19812 0.4064) (xy -0.2032 0.39624) (xy -0.20701 0.38735) (xy -0.21209 0.37719)
						(xy -0.2159 0.36703) (xy -0.21844 0.35687) (xy -0.22225 0.34544) (xy -0.22352 0.33528) (xy -0.22606 0.32512)
						(xy -0.22733 0.31369) (xy -0.22733 0.30353) (xy -0.2286 0.2921) (xy -0.22733 0.28067) (xy -0.22733 0.27051)
						(xy -0.22606 0.25908) (xy -0.22352 0.24892) (xy -0.22225 0.23876) (xy -0.21844 0.22733) (xy -0.2159 0.21717)
						(xy -0.21209 0.20701) (xy -0.20701 0.19685) (xy -0.2032 0.18796) (xy -0.19812 0.1778) (xy -0.17272 0.14224)
						(xy -0.1651 0.13462) (xy -0.1651 -0.7366) (xy -0.16256 -0.76835) (xy -0.1524 -0.8001) (xy -0.13716 -0.82804)
						(xy -0.11684 -0.85344) (xy -0.09144 -0.87376) (xy -0.0635 -0.889) (xy -0.03175 -0.89916) (xy 0 -0.9017)
						(xy 0.03175 -0.89916) (xy 0.0635 -0.889) (xy 0.09144 -0.87376) (xy 0.11684 -0.85344) (xy 0.13716 -0.82804)
						(xy 0.1524 -0.8001) (xy 0.16256 -0.76835) (xy 0.1651 -0.7366) (xy 0.1651 0.13462) (xy 0.17272 0.14224)
						(xy 0.19812 0.1778) (xy 0.2032 0.18796) (xy 0.20701 0.19685) (xy 0.21209 0.20701) (xy 0.2159 0.21717)
						(xy 0.21844 0.22733) (xy 0.22225 0.23876) (xy 0.22352 0.24892) (xy 0.22606 0.25908) (xy 0.22733 0.27051)
						(xy 0.22733 0.28067) (xy 0.2286 0.2921) (xy 0.22733 0.30353) (xy 0.22733 0.31369) (xy 0.22606 0.32512)
						(xy 0.22352 0.33528) (xy 0.22225 0.34544) (xy 0.21844 0.35687) (xy 0.2159 0.36703) (xy 0.21209 0.37719)
						(xy 0.20701 0.38735) (xy 0.2032 0.39624) (xy 0.19812 0.4064) (xy 0.17272 0.44196) (xy 0.1651 0.44958)
						(xy 0.1651 0.7366) (xy 0.16256 0.76835) (xy 0.1524 0.8001) (xy 0.13716 0.82804) (xy 0.11684 0.85344)
						(xy 0.09144 0.87376) (xy 0.0635 0.889) (xy 0.03175 0.89916)
					)
					(width 0)
					(fill yes)
				)
			)
		)
	)
)
